(kicad_pcb
	(version 20260206)
	(generator "pcbnew")
	(generator_version "10.0")
	(general
		(thickness 1.6)
		(legacy_teardrops no)
	)
	(paper "A4")
	(title_block
		(title "Bryce Canyon_SCC_16316-1_OCP.brd")
		(comment 1 "Bryce Canyon / footprints 139-145 of 1561")
	)
	(layers
		(0 "F.Cu" signal "TOP")
		(4 "In1.Cu" signal "L2GND")
		(6 "In2.Cu" signal "L3")
		(8 "In3.Cu" signal "L4VCC")
		(10 "In4.Cu" signal "L5VCC")
		(12 "In5.Cu" signal "L6")
		(14 "In6.Cu" signal "L7GND")
		(2 "B.Cu" signal "BOTTOM")
		(9 "F.Adhes" user "F.Adhesive")
		(11 "B.Adhes" user "B.Adhesive")
		(13 "F.Paste" user "Package Geometry/Pastemask Top")
		(15 "B.Paste" user "Package Geometry/Pastemask Bottom")
		(5 "F.SilkS" user "Ref Des/Silkscreen Top")
		(7 "B.SilkS" user "Ref Des/Silkscreen Bottom")
		(1 "F.Mask" user "Board Geometry/Soldermask Top")
		(3 "B.Mask" user "Board Geometry/Soldermask Bottom")
		(17 "Dwgs.User" user "User.Drawings")
		(19 "Cmts.User" user "User.Comments")
		(21 "Eco1.User" user "User.Eco1")
		(23 "Eco2.User" user "User.Eco2")
		(25 "Edge.Cuts" user "Board Geometry/Outline")
		(27 "Margin" user)
		(31 "F.CrtYd" user "Package Geometry/Place Bound Top")
		(29 "B.CrtYd" user "Package Geometry/Place Bound Bottom")
		(35 "F.Fab" user "Ref Des/Assembly Top")
		(33 "B.Fab" user "Ref Des/Assembly Bottom")
	)
	(footprint ""
		(layer "F.Cu")
		(at 186.44616 -111.14786)
		(property "Reference" "Q34"
			(at 0 0 0)
			(layer "F.SilkS")
			(hide yes)
			(effects
				(font
					(size 1.27 1.27)
				)
			)
		)
		(property "Value" "2N7002E-2-GP"
			(at 0.127 -8.9662 0)
			(unlocked yes)
			(layer "F.Fab")
			(hide yes)
			(effects
				(font
					(size 1.016 1.016)
					(thickness 0.1524)
				)
			)
		)
		(property "Device Type" "SOT23DGS2D4H44"
			(at 0.127 -10.4902 0)
			(unlocked yes)
			(layer "F.Fab")
			(hide yes)
			(effects
				(font
					(size 1.016 1.016)
					(thickness 0.1524)
				)
			)
		)
		(duplicate_pad_numbers_are_jumpers no)
		(fp_line
			(start -1.651 -1.778)
			(end -1.651 1.778)
			(stroke
				(width 0.1524)
				(type default)
			)
			(layer "F.SilkS")
		)
		(fp_line
			(start -1.651 1.778)
			(end 1.651 1.778)
			(stroke
				(width 0.1524)
				(type default)
			)
			(layer "F.SilkS")
		)
		(fp_line
			(start 1.651 -1.778)
			(end -1.651 -1.778)
			(stroke
				(width 0.1524)
				(type default)
			)
			(layer "F.SilkS")
		)
		(fp_line
			(start 1.651 1.778)
			(end 1.651 -1.778)
			(stroke
				(width 0.1524)
				(type default)
			)
			(layer "F.SilkS")
		)
		(fp_poly
			(pts
				(xy -1.778 1.8796) (xy -1.778 -1.8796) (xy 1.778 -1.8796) (xy 1.778 1.8796)
			)
			(stroke
				(width 0)
				(type default)
			)
			(fill no)
			(layer "F.CrtYd")
		)
		(fp_poly
			(pts
				(xy -1.778 1.8796) (xy -1.778 -1.8796) (xy 1.778 -1.8796) (xy 1.778 1.8796)
			)
			(stroke
				(width 0)
				(type default)
			)
			(fill no)
			(layer "F.Fab")
		)
		(pad "D" smd custom
			(at 0 -0.9525)
			(size 0.1905 0.1905)
			(layers "F.Cu" "F.Mask" "F.Paste")
			(net "P1V8_C_G_PG")
			(options
				(clearance outline)
				(anchor circle)
			)
			(primitives
				(gr_poly
					(pts
						(arc
							(start -0.1778 0.5715)
							(mid -0.321484 0.511984)
							(end -0.381 0.3683)
						)
						(arc
							(start -0.381 -0.3683)
							(mid -0.321484 -0.511984)
							(end -0.1778 -0.5715)
						)
						(arc
							(start 0.1778 -0.5715)
							(mid 0.321484 -0.511984)
							(end 0.381 -0.3683)
						)
						(arc
							(start 0.381 0.3683)
							(mid 0.321484 0.511984)
							(end 0.1778 0.5715)
						)
					)
					(width 0)
					(fill yes)
				)
			)
		)
		(pad "G" smd custom
			(at -0.98425 0.9525)
			(size 0.1905 0.1905)
			(layers "F.Cu" "F.Mask" "F.Paste")
			(net "P0V9_G_PG")
			(options
				(clearance outline)
				(anchor circle)
			)
			(primitives
				(gr_poly
					(pts
						(arc
							(start -0.1778 0.5715)
							(mid -0.321484 0.511984)
							(end -0.381 0.3683)
						)
						(arc
							(start -0.381 -0.3683)
							(mid -0.321484 -0.511984)
							(end -0.1778 -0.5715)
						)
						(arc
							(start 0.1778 -0.5715)
							(mid 0.321484 -0.511984)
							(end 0.381 -0.3683)
						)
						(arc
							(start 0.381 0.3683)
							(mid 0.321484 0.511984)
							(end 0.1778 0.5715)
						)
					)
					(width 0)
					(fill yes)
				)
			)
		)
		(pad "S" smd custom
			(at 0.98425 0.9525)
			(size 0.1905 0.1905)
			(layers "F.Cu" "F.Mask" "F.Paste")
			(net "P1V8_C_S")
			(options
				(clearance outline)
				(anchor circle)
			)
			(primitives
				(gr_poly
					(pts
						(arc
							(start -0.1778 0.5715)
							(mid -0.321484 0.511984)
							(end -0.381 0.3683)
						)
						(arc
							(start -0.381 -0.3683)
							(mid -0.321484 -0.511984)
							(end -0.1778 -0.5715)
						)
						(arc
							(start 0.1778 -0.5715)
							(mid 0.321484 -0.511984)
							(end 0.381 -0.3683)
						)
						(arc
							(start 0.381 0.3683)
							(mid 0.321484 0.511984)
							(end 0.1778 0.5715)
						)
					)
					(width 0)
					(fill yes)
				)
			)
		)
	)
	(footprint ""
		(layer "F.Cu")
		(at 70.612 -35.814 90)
		(property "Reference" "R161"
			(at 0 0 90)
			(layer "F.SilkS")
			(hide yes)
			(effects
				(font
					(size 1.27 1.27)
				)
			)
		)
		(property "Value" "D51R3F-2-GP"
			(at -0.0254 -2.5146 90)
			(unlocked yes)
			(layer "F.Fab")
			(hide yes)
			(effects
				(font
					(size 1.016 1.016)
					(thickness 0.1524)
				)
			)
		)
		(property "Device Type" "R603H22"
			(at -0.0254 -4.0386 90)
			(unlocked yes)
			(layer "F.Fab")
			(hide yes)
			(effects
				(font
					(size 1.016 1.016)
					(thickness 0.1524)
				)
			)
		)
		(duplicate_pad_numbers_are_jumpers no)
		(fp_line
			(start 0.2032 0)
			(end 0.4826 0)
			(stroke
				(width 0.2032)
				(type default)
			)
			(layer "F.SilkS")
		)
		(fp_line
			(start -0.4826 0)
			(end -0.2032 0)
			(stroke
				(width 0.2032)
				(type default)
			)
			(layer "F.SilkS")
		)
		(fp_rect
			(start -0.5842 1.3335)
			(end 0.5842 -1.3335)
			(stroke
				(width 0)
				(type default)
			)
			(fill no)
			(layer "F.CrtYd")
		)
		(fp_rect
			(start -0.5842 1.3335)
			(end 0.5842 -1.3335)
			(stroke
				(width 0)
				(type default)
			)
			(fill no)
			(layer "F.Fab")
		)
		(pad "1" smd custom
			(at 0 -0.762 90)
			(size 0.2159 0.2159)
			(layers "F.Cu" "F.Mask" "F.Paste")
			(net "P0V9")
			(options
				(clearance outline)
				(anchor circle)
			)
			(primitives
				(gr_poly
					(pts
						(arc
							(start -0.3302 -0.4318)
							(mid -0.402042 -0.402042)
							(end -0.4318 -0.3302)
						)
						(arc
							(start -0.4318 0.3302)
							(mid -0.402042 0.402042)
							(end -0.3302 0.4318)
						)
						(arc
							(start 0.3302 0.4318)
							(mid 0.402042 0.402042)
							(end 0.4318 0.3302)
						)
						(arc
							(start 0.4318 -0.3302)
							(mid 0.402042 -0.402042)
							(end 0.3302 -0.4318)
						)
					)
					(width 0)
					(fill yes)
				)
			)
		)
		(pad "2" smd custom
			(at 0 0.762 90)
			(size 0.2159 0.2159)
			(layers "F.Cu" "F.Mask" "F.Paste")
			(net "GB_VDDA")
			(options
				(clearance outline)
				(anchor circle)
			)
			(primitives
				(gr_poly
					(pts
						(arc
							(start -0.3302 -0.4318)
							(mid -0.402042 -0.402042)
							(end -0.4318 -0.3302)
						)
						(arc
							(start -0.4318 0.3302)
							(mid -0.402042 0.402042)
							(end -0.3302 0.4318)
						)
						(arc
							(start 0.3302 0.4318)
							(mid 0.402042 0.402042)
							(end 0.4318 0.3302)
						)
						(arc
							(start 0.4318 -0.3302)
							(mid 0.402042 -0.402042)
							(end 0.3302 -0.4318)
						)
					)
					(width 0)
					(fill yes)
				)
			)
		)
	)
	(footprint ""
		(layer "F.Cu")
		(at 72.4916 -81.0514 180)
		(property "Reference" "R573"
			(at 0 0 180)
			(layer "F.SilkS")
			(hide yes)
			(effects
				(font
					(size 1.27 1.27)
				)
			)
		)
		(property "Value" "0R2J-2-GP"
			(at 0.064008 -3.993896 180)
			(unlocked yes)
			(layer "F.Fab")
			(hide yes)
			(effects
				(font
					(size 1.016 1.016)
					(thickness 0.1524)
				)
			)
		)
		(property "Device Type" "R402H16"
			(at 0.064008 -5.517896 180)
			(unlocked yes)
			(layer "F.Fab")
			(hide yes)
			(effects
				(font
					(size 1.016 1.016)
					(thickness 0.1524)
				)
			)
		)
		(duplicate_pad_numbers_are_jumpers no)
		(fp_line
			(start 0.508 -0.9398)
			(end -0.508 -0.9398)
			(stroke
				(width 0.1524)
				(type default)
			)
			(layer "F.SilkS")
		)
		(fp_line
			(start -0.508 -0.9398)
			(end -0.508 0.9398)
			(stroke
				(width 0.1524)
				(type default)
			)
			(layer "F.SilkS")
		)
		(fp_rect
			(start -0.508 0.9398)
			(end 0.508 -0.9398)
			(stroke
				(width 0)
				(type default)
			)
			(fill no)
			(layer "F.CrtYd")
		)
		(fp_rect
			(start -0.508 0.9398)
			(end 0.508 -0.9398)
			(stroke
				(width 0)
				(type default)
			)
			(fill no)
			(layer "F.Fab")
		)
		(pad "1" smd custom
			(at 0 -0.4445 180)
			(size 0.1397 0.1397)
			(layers "F.Cu" "F.Mask" "F.Paste")
			(net "PCIE_COMP_TO_SCC_RST_R_0")
			(options
				(clearance outline)
				(anchor circle)
			)
			(primitives
				(gr_poly
					(pts
						(arc
							(start -0.1778 -0.2794)
							(mid -0.249642 -0.249642)
							(end -0.2794 -0.1778)
						)
						(arc
							(start -0.2794 0.1778)
							(mid -0.249642 0.249642)
							(end -0.1778 0.2794)
						)
						(arc
							(start 0.1778 0.2794)
							(mid 0.249642 0.249642)
							(end 0.2794 0.1778)
						)
						(arc
							(start 0.2794 -0.1778)
							(mid 0.249642 -0.249642)
							(end 0.1778 -0.2794)
						)
					)
					(width 0)
					(fill yes)
				)
			)
		)
		(pad "2" smd custom
			(at 0 0.4445 180)
			(size 0.1397 0.1397)
			(layers "F.Cu" "F.Mask" "F.Paste")
			(net "PCIE_COMP_TO_SCC_RST_0")
			(options
				(clearance outline)
				(anchor circle)
			)
			(primitives
				(gr_poly
					(pts
						(arc
							(start -0.1778 -0.2794)
							(mid -0.249642 -0.249642)
							(end -0.2794 -0.1778)
						)
						(arc
							(start -0.2794 0.1778)
							(mid -0.249642 0.249642)
							(end -0.1778 0.2794)
						)
						(arc
							(start 0.1778 0.2794)
							(mid 0.249642 0.249642)
							(end 0.2794 0.1778)
						)
						(arc
							(start 0.2794 -0.1778)
							(mid 0.249642 -0.249642)
							(end 0.1778 -0.2794)
						)
					)
					(width 0)
					(fill yes)
				)
			)
		)
	)
	(footprint ""
		(layer "F.Cu")
		(at 20.9804 -57.277 180)
		(property "Reference" "C653"
			(at 0 0 180)
			(layer "F.SilkS")
			(hide yes)
			(effects
				(font
					(size 1.27 1.27)
				)
			)
		)
		(property "Value" "SCD1U50V3KX-GP"
			(at 0 -2.8194 180)
			(unlocked yes)
			(layer "F.Fab")
			(hide yes)
			(effects
				(font
					(size 1.016 1.016)
					(thickness 0.1524)
				)
			)
		)
		(property "Device Type" "C603H36"
			(at 0 -4.3434 180)
			(unlocked yes)
			(layer "F.Fab")
			(hide yes)
			(effects
				(font
					(size 1.016 1.016)
					(thickness 0.1524)
				)
			)
		)
		(duplicate_pad_numbers_are_jumpers no)
		(fp_line
			(start 0.508 0)
			(end -0.508 0)
			(stroke
				(width 0.2032)
				(type default)
			)
			(layer "F.SilkS")
		)
		(fp_rect
			(start -0.5842 1.3335)
			(end 0.5842 -1.3335)
			(stroke
				(width 0)
				(type default)
			)
			(fill no)
			(layer "F.CrtYd")
		)
		(fp_rect
			(start -0.5842 1.3335)
			(end 0.5842 -1.3335)
			(stroke
				(width 0)
				(type default)
			)
			(fill no)
			(layer "F.Fab")
		)
		(pad "1" smd custom
			(at 0 -0.762 180)
			(size 0.2159 0.2159)
			(layers "F.Cu" "F.Mask" "F.Paste")
			(net "MB0_ISTART_R")
			(options
				(clearance outline)
				(anchor circle)
			)
			(primitives
				(gr_poly
					(pts
						(arc
							(start -0.3302 -0.4318)
							(mid -0.402042 -0.402042)
							(end -0.4318 -0.3302)
						)
						(arc
							(start -0.4318 0.3302)
							(mid -0.402042 0.402042)
							(end -0.3302 0.4318)
						)
						(arc
							(start 0.3302 0.4318)
							(mid 0.402042 0.402042)
							(end 0.4318 0.3302)
						)
						(arc
							(start 0.4318 -0.3302)
							(mid 0.402042 -0.402042)
							(end 0.3302 -0.4318)
						)
					)
					(width 0)
					(fill yes)
				)
			)
		)
		(pad "2" smd custom
			(at 0 0.762 180)
			(size 0.2159 0.2159)
			(layers "F.Cu" "F.Mask" "F.Paste")
			(net "AGND_CURRENT_MON")
			(options
				(clearance outline)
				(anchor circle)
			)
			(primitives
				(gr_poly
					(pts
						(arc
							(start -0.3302 -0.4318)
							(mid -0.402042 -0.402042)
							(end -0.4318 -0.3302)
						)
						(arc
							(start -0.4318 0.3302)
							(mid -0.402042 0.402042)
							(end -0.3302 0.4318)
						)
						(arc
							(start 0.3302 0.4318)
							(mid 0.402042 0.402042)
							(end 0.4318 0.3302)
						)
						(arc
							(start 0.4318 -0.3302)
							(mid 0.402042 -0.402042)
							(end 0.3302 -0.4318)
						)
					)
					(width 0)
					(fill yes)
				)
			)
		)
	)
	(footprint ""
		(layer "F.Cu")
		(at 15.00632 -101.44506 -90)
		(property "Reference" "C738"
			(at 0 0 270)
			(layer "F.SilkS")
			(hide yes)
			(effects
				(font
					(size 1.27 1.27)
				)
			)
		)
		(property "Value" "SCD1U16V2KX-3GP"
			(at 1.1811 -2.7051 270)
			(unlocked yes)
			(layer "F.Fab")
			(hide yes)
			(effects
				(font
					(size 1.016 1.016)
					(thickness 0.1524)
				)
			)
		)
		(property "Device Type" "C402H22"
			(at 1.1811 -4.2291 270)
			(unlocked yes)
			(layer "F.Fab")
			(hide yes)
			(effects
				(font
					(size 1.016 1.016)
					(thickness 0.1524)
				)
			)
		)
		(duplicate_pad_numbers_are_jumpers no)
		(fp_rect
			(start -0.4318 0.9525)
			(end 0.4318 -0.9525)
			(stroke
				(width 0)
				(type default)
			)
			(fill no)
			(layer "F.CrtYd")
		)
		(fp_rect
			(start -0.4318 0.9525)
			(end 0.4318 -0.9525)
			(stroke
				(width 0)
				(type default)
			)
			(fill no)
			(layer "F.Fab")
		)
		(pad "1" smd custom
			(at 0 -0.4445 270)
			(size 0.1524 0.1524)
			(layers "F.Cu" "F.Mask" "F.Paste")
			(net "U119_EN")
			(options
				(clearance outline)
				(anchor circle)
			)
			(primitives
				(gr_poly
					(pts
						(arc
							(start 0.3048 -0.2032)
							(mid 0.275042 -0.275042)
							(end 0.2032 -0.3048)
						)
						(arc
							(start -0.2032 -0.3048)
							(mid -0.275042 -0.275042)
							(end -0.3048 -0.2032)
						)
						(arc
							(start -0.3048 0.2032)
							(mid -0.275042 0.275042)
							(end -0.2032 0.3048)
						)
						(arc
							(start 0.2032 0.3048)
							(mid 0.275042 0.275042)
							(end 0.3048 0.2032)
						)
					)
					(width 0)
					(fill yes)
				)
			)
		)
		(pad "2" smd custom
			(at 0 0.4445 270)
			(size 0.1524 0.1524)
			(layers "F.Cu" "F.Mask" "F.Paste")
			(net "GND")
			(options
				(clearance outline)
				(anchor circle)
			)
			(primitives
				(gr_poly
					(pts
						(arc
							(start 0.3048 -0.2032)
							(mid 0.275042 -0.275042)
							(end 0.2032 -0.3048)
						)
						(arc
							(start -0.2032 -0.3048)
							(mid -0.275042 -0.275042)
							(end -0.3048 -0.2032)
						)
						(arc
							(start -0.3048 0.2032)
							(mid -0.275042 0.275042)
							(end -0.2032 0.3048)
						)
						(arc
							(start 0.2032 0.3048)
							(mid 0.275042 0.275042)
							(end 0.3048 0.2032)
						)
					)
					(width 0)
					(fill yes)
				)
			)
		)
	)
	(footprint ""
		(layer "F.Cu")
		(at 43.7642 -49.7332 180)
		(property "Reference" "C670"
			(at 0 0 180)
			(layer "F.SilkS")
			(hide yes)
			(effects
				(font
					(size 1.27 1.27)
				)
			)
		)
		(property "Value" "SC10U16V5KX-7-GP-U"
			(at -0.0762 -6.1214 180)
			(unlocked yes)
			(layer "F.Fab")
			(hide yes)
			(effects
				(font
					(size 1.016 1.016)
					(thickness 0.1524)
				)
			)
		)
		(property "Device Type" "C805H58"
			(at -0.0762 -8.1534 180)
			(unlocked yes)
			(layer "F.Fab")
			(hide yes)
			(effects
				(font
					(size 1.016 1.016)
					(thickness 0.1524)
				)
			)
		)
		(duplicate_pad_numbers_are_jumpers no)
		(fp_line
			(start 0.635 0)
			(end -0.635 0)
			(stroke
				(width 0.508)
				(type default)
			)
			(layer "F.SilkS")
		)
		(fp_rect
			(start -0.9652 1.778)
			(end 0.9652 -1.778)
			(stroke
				(width 0)
				(type default)
			)
			(fill no)
			(layer "F.CrtYd")
		)
		(fp_poly
			(pts
				(xy -0.9652 -1.778) (xy 0.9652 -1.778) (xy 0.9652 1.778) (xy -0.9652 1.778)
			)
			(stroke
				(width 0)
				(type default)
			)
			(fill no)
			(layer "F.Fab")
		)
		(pad "1" smd rect
			(at 0 -0.9652 180)
			(size 1.397 1.143)
			(layers "F.Cu" "F.Mask" "F.Paste")
			(net "P12V_STBY_VIN_Q7")
		)
		(pad "2" smd rect
			(at 0 0.9652 180)
			(size 1.397 1.143)
			(layers "F.Cu" "F.Mask" "F.Paste")
			(net "GND")
		)
	)
	(footprint ""
		(layer "F.Cu")
		(at 55.88 -122.936 -90)
		(property "Reference" "C705"
			(at 0 0 270)
			(layer "F.SilkS")
			(hide yes)
			(effects
				(font
					(size 1.27 1.27)
				)
			)
		)
		(property "Value" "SCD1U16V2KX-3GP"
			(at 1.1811 -2.7051 270)
			(unlocked yes)
			(layer "F.Fab")
			(hide yes)
			(effects
				(font
					(size 1.016 1.016)
					(thickness 0.1524)
				)
			)
		)
		(property "Device Type" "C402H22"
			(at 1.1811 -4.2291 270)
			(unlocked yes)
			(layer "F.Fab")
			(hide yes)
			(effects
				(font
					(size 1.016 1.016)
					(thickness 0.1524)
				)
			)
		)
		(duplicate_pad_numbers_are_jumpers no)
		(fp_rect
			(start -0.4318 0.9525)
			(end 0.4318 -0.9525)
			(stroke
				(width 0)
				(type default)
			)
			(fill no)
			(layer "F.CrtYd")
		)
		(fp_rect
			(start -0.4318 0.9525)
			(end 0.4318 -0.9525)
			(stroke
				(width 0)
				(type default)
			)
			(fill no)
			(layer "F.Fab")
		)
		(pad "1" smd custom
			(at 0 -0.4445 270)
			(size 0.1524 0.1524)
			(layers "F.Cu" "F.Mask" "F.Paste")
			(net "P3V3_OUT")
			(options
				(clearance outline)
				(anchor circle)
			)
			(primitives
				(gr_poly
					(pts
						(arc
							(start 0.3048 -0.2032)
							(mid 0.275042 -0.275042)
							(end 0.2032 -0.3048)
						)
						(arc
							(start -0.2032 -0.3048)
							(mid -0.275042 -0.275042)
							(end -0.3048 -0.2032)
						)
						(arc
							(start -0.3048 0.2032)
							(mid -0.275042 0.275042)
							(end -0.2032 0.3048)
						)
						(arc
							(start 0.2032 0.3048)
							(mid 0.275042 0.275042)
							(end 0.3048 0.2032)
						)
					)
					(width 0)
					(fill yes)
				)
			)
		)
		(pad "2" smd custom
			(at 0 0.4445 270)
			(size 0.1524 0.1524)
			(layers "F.Cu" "F.Mask" "F.Paste")
			(net "GND")
			(options
				(clearance outline)
				(anchor circle)
			)
			(primitives
				(gr_poly
					(pts
						(arc
							(start 0.3048 -0.2032)
							(mid 0.275042 -0.275042)
							(end 0.2032 -0.3048)
						)
						(arc
							(start -0.2032 -0.3048)
							(mid -0.275042 -0.275042)
							(end -0.3048 -0.2032)
						)
						(arc
							(start -0.3048 0.2032)
							(mid -0.275042 0.275042)
							(end -0.2032 0.3048)
						)
						(arc
							(start 0.2032 0.3048)
							(mid 0.275042 0.275042)
							(end 0.3048 0.2032)
						)
					)
					(width 0)
					(fill yes)
				)
			)
		)
	)
)
